# BASEBOARD_FAB2 (Tioga Pass) — schematic netlist excerpt (pin names and nets, part order shuffled) for the footprints in the layout excerpt that follows; sources: Cadence DE-HDL packaged netlist, KiCad conversion of Wiwynn_Tioga_Pass_MB.brd

C9W16  CAP_A  22.0UF 4V 20% X6S  pkg 0603V  page 238 : A = P1V15_AUX_BMC ; B = GND
C8U13  CAP_A  47UF 4V 20% X5R  pkg 0603V  page 225 : A = PVDDQ_GHJ ; B = GND
C7M4  CAP  10UF 4V 20% X6S  pkg 0603LF  page 234 : A = PVPP_KLM ; B = GND

(kicad_pcb
	(version 20260206)
	(generator "pcbnew")
	(generator_version "10.0")
	(general
		(thickness 1.6)
		(legacy_teardrops no)
	)
	(paper "A4")
	(title_block
		(title "Wiwynn_Tioga_Pass_MB.brd")
		(comment 1 "Tioga Pass / footprints 3343-3345 of 4770")
	)
	(layers
		(0 "F.Cu" signal "TOP")
		(4 "In1.Cu" signal "L2GND")
		(6 "In2.Cu" signal "L3")
		(8 "In3.Cu" signal "L4GND")
		(10 "In4.Cu" signal "L5")
		(12 "In5.Cu" signal "L6GND")
		(14 "In6.Cu" signal "L7VCC")
		(16 "In7.Cu" signal "L8VCC")
		(18 "In8.Cu" signal "L9GND")
		(20 "In9.Cu" signal "L10")
		(22 "In10.Cu" signal "L11GND")
		(24 "In11.Cu" signal "L12")
		(26 "In12.Cu" signal "L13GND")
		(2 "B.Cu" signal "BOTTOM")
		(9 "F.Adhes" user "F.Adhesive")
		(11 "B.Adhes" user "B.Adhesive")
		(13 "F.Paste" user "Package Geometry/Pastemask Top")
		(15 "B.Paste" user "Package Geometry/Pastemask Bottom")
		(5 "F.SilkS" user "Ref Des/Silkscreen Top")
		(7 "B.SilkS" user "Ref Des/Silkscreen Bottom")
		(1 "F.Mask" user "Board Geometry/Soldermask Top")
		(3 "B.Mask" user "Board Geometry/Soldermask Bottom")
		(17 "Dwgs.User" user "User.Drawings")
		(19 "Cmts.User" user "User.Comments")
		(21 "Eco1.User" user "User.Eco1")
		(23 "Eco2.User" user "User.Eco2")
		(25 "Edge.Cuts" user "Board Geometry/Outline")
		(27 "Margin" user)
		(31 "F.CrtYd" user "Package Geometry/Place Bound Top")
		(29 "B.CrtYd" user "Package Geometry/Place Bound Bottom")
		(35 "F.Fab" user "Ref Des/Assembly Top")
		(33 "B.Fab" user "Ref Des/Assembly Bottom")
	)
	(footprint ""
		(layer "B.Cu")
		(at 458.0001 -41.51376 -90)
		(property "Reference" "C9W16"
			(at -0.97536 0.76708 0)
			(unlocked yes)
			(layer "B.SilkS")
			(effects
				(font
					(size 0.4064 0.254)
					(thickness 0.1524)
				)
				(justify mirror)
			)
		)
		(property "Value" ""
			(at 0 0 90)
			(layer "B.Fab")
			(effects
				(font
					(size 1.27 1.27)
				)
				(justify mirror)
			)
		)
		(duplicate_pad_numbers_are_jumpers no)
		(fp_poly
			(pts
				(xy 0.4953 -0.2032) (xy -0.4953 -0.2032) (xy -0.4953 1.6002) (xy 0.4953 1.6002)
			)
			(stroke
				(width 0)
				(type default)
			)
			(fill no)
			(layer "B.CrtYd")
		)
		(fp_line
			(start -0.4953 1.6002)
			(end 0.4953 1.6002)
			(stroke
				(width 0.1)
				(type default)
			)
			(layer "B.Fab")
		)
		(fp_line
			(start 0.4953 1.6002)
			(end 0.4953 -0.2032)
			(stroke
				(width 0.1)
				(type default)
			)
			(layer "B.Fab")
		)
		(fp_line
			(start -0.4953 -0.2032)
			(end -0.4953 1.6002)
			(stroke
				(width 0.1)
				(type default)
			)
			(layer "B.Fab")
		)
		(fp_line
			(start 0.4953 -0.2032)
			(end -0.4953 -0.2032)
			(stroke
				(width 0.1)
				(type default)
			)
			(layer "B.Fab")
		)
		(pad "1" smd rect
			(at 0 0 90)
			(size 0.762 0.889)
			(layers "B.Cu" "B.Mask" "B.Paste")
			(net "P1V15_AUX_BMC")
		)
		(pad "2" smd rect
			(at 0 1.397 90)
			(size 0.762 0.889)
			(layers "B.Cu" "B.Mask" "B.Paste")
			(net "GND")
		)
		(zone
			(layer "B.Cu")
			(hatch none 0.5)
			(connect_pads
				(clearance 0)
			)
			(min_thickness 0.25)
			(keepout
				(tracks not_allowed)
				(vias allowed)
				(pads allowed)
				(copperpour not_allowed)
				(footprints allowed)
			)
			(placement
				(enabled no)
				(sheetname "")
			)
			(fill
				(thermal_gap 0.5)
				(thermal_bridge_width 0.5)
				(island_removal_mode 0)
			)
			(polygon
				(pts
					(xy 457.5556 -41.13276) (xy 457.5556 -41.89476) (xy 457.0476 -41.89476) (xy 457.0476 -41.13276)
				)
			)
		)
	)
	(footprint ""
		(layer "B.Cu")
		(at 154.023568 -135.376412 -90)
		(property "Reference" "C7M4"
			(at 0 0 90)
			(layer "B.SilkS")
			(hide yes)
			(effects
				(font
					(size 1.27 1.27)
				)
				(justify mirror)
			)
		)
		(property "Value" ""
			(at 0 0 90)
			(layer "B.Fab")
			(effects
				(font
					(size 1.27 1.27)
				)
				(justify mirror)
			)
		)
		(duplicate_pad_numbers_are_jumpers no)
		(fp_rect
			(start 0.4953 1.6002)
			(end -0.4953 -0.2032)
			(stroke
				(width 0)
				(type default)
			)
			(fill no)
			(layer "B.CrtYd")
		)
		(fp_line
			(start -0.4953 1.6002)
			(end 0.4953 1.6002)
			(stroke
				(width 0.1)
				(type default)
			)
			(layer "B.Fab")
		)
		(fp_line
			(start 0.4953 1.6002)
			(end 0.4953 -0.2032)
			(stroke
				(width 0.1)
				(type default)
			)
			(layer "B.Fab")
		)
		(fp_line
			(start -0.4953 -0.2032)
			(end -0.4953 1.6002)
			(stroke
				(width 0.1)
				(type default)
			)
			(layer "B.Fab")
		)
		(fp_line
			(start 0.4953 -0.2032)
			(end -0.4953 -0.2032)
			(stroke
				(width 0.1)
				(type default)
			)
			(layer "B.Fab")
		)
		(pad "1" smd rect
			(at 0 0 90)
			(size 0.762 0.889)
			(layers "B.Cu" "B.Mask" "B.Paste")
			(net "PVPP_KLM")
		)
		(pad "2" smd rect
			(at 0 1.397 90)
			(size 0.762 0.889)
			(layers "B.Cu" "B.Mask" "B.Paste")
			(net "GND")
		)
		(zone
			(layer "B.Cu")
			(hatch none 0.5)
			(connect_pads
				(clearance 0)
			)
			(min_thickness 0.25)
			(keepout
				(tracks not_allowed)
				(vias allowed)
				(pads allowed)
				(copperpour not_allowed)
				(footprints allowed)
			)
			(placement
				(enabled no)
				(sheetname "")
			)
			(fill
				(thermal_gap 0.5)
				(thermal_bridge_width 0.5)
				(island_removal_mode 0)
			)
			(polygon
				(pts
					(xy 153.071068 -134.995412) (xy 153.579068 -134.995412) (xy 153.579068 -135.757412) (xy 153.071068 -135.757412)
				)
			)
		)
	)
	(footprint ""
		(layer "B.Cu")
		(at 100.6856 3.8862 -90)
		(property "Reference" "C8U13"
			(at 0 0 90)
			(layer "B.SilkS")
			(hide yes)
			(effects
				(font
					(size 1.27 1.27)
				)
				(justify mirror)
			)
		)
		(property "Value" ""
			(at 0 0 90)
			(layer "B.Fab")
			(effects
				(font
					(size 1.27 1.27)
				)
				(justify mirror)
			)
		)
		(duplicate_pad_numbers_are_jumpers no)
		(fp_rect
			(start 0.500126 1.598422)
			(end -0.500126 -0.201422)
			(stroke
				(width 0)
				(type default)
			)
			(fill no)
			(layer "B.CrtYd")
		)
		(fp_line
			(start -0.500126 1.598422)
			(end 0.500126 1.598422)
			(stroke
				(width 0.1)
				(type default)
			)
			(layer "B.Fab")
		)
		(fp_line
			(start 0.500126 1.598422)
			(end 0.500126 -0.201422)
			(stroke
				(width 0.1)
				(type default)
			)
			(layer "B.Fab")
		)
		(fp_line
			(start -0.500126 -0.201422)
			(end -0.500126 1.598422)
			(stroke
				(width 0.1)
				(type default)
			)
			(layer "B.Fab")
		)
		(fp_line
			(start 0.500126 -0.201422)
			(end -0.500126 -0.201422)
			(stroke
				(width 0.1)
				(type default)
			)
			(layer "B.Fab")
		)
		(pad "1" smd rect
			(at 0 0 180)
			(size 0.889 0.9906)
			(layers "B.Cu" "B.Mask" "B.Paste")
			(net "PVDDQ_GHJ")
		)
		(pad "2" smd rect
			(at 0 1.397 180)
			(size 0.889 0.9906)
			(layers "B.Cu" "B.Mask" "B.Paste")
			(net "GND")
		)
		(zone
			(layer "B.Cu")
			(hatch none 0.5)
			(connect_pads
				(clearance 0)
			)
			(min_thickness 0.25)
			(keepout
				(tracks allowed)
				(vias not_allowed)
				(pads allowed)
				(copperpour not_allowed)
				(footprints allowed)
			)
			(placement
				(enabled no)
				(sheetname "")
			)
			(fill
				(thermal_gap 0.5)
				(thermal_bridge_width 0.5)
				(island_removal_mode 0)
			)
			(polygon
				(pts
					(xy 99.7331 4.3815) (xy 100.2411 4.3815) (xy 100.2411 3.3909) (xy 99.7331 3.3909)
				)
			)
		)
		(zone
			(layer "B.Cu")
			(hatch none 0.5)
			(connect_pads
				(clearance 0)
			)
			(min_thickness 0.25)
			(keepout
				(tracks not_allowed)
				(vias allowed)
				(pads allowed)
				(copperpour not_allowed)
				(footprints allowed)
			)
			(placement
				(enabled no)
				(sheetname "")
			)
			(fill
				(thermal_gap 0.5)
				(thermal_bridge_width 0.5)
				(island_removal_mode 0)
			)
			(polygon
				(pts
					(xy 99.7331 4.3815) (xy 100.2411 4.3815) (xy 100.2411 3.3909) (xy 99.7331 3.3909)
				)
			)
		)
	)
)
